FILE_TYPE=LIBRARY_PARTS;
PRIMITIVE 'BATTERY';
  PIN
  END_PIN;
  BODY
    CLASS='MECHANICAL';
    PART_NAME='BATTERY';
    PINCOUNT='0';
    BODY_NAME='BATTERY';
    PHYS_DES_PREFIX='XBT';
  END_BODY;
END_PRIMITIVE;
END.

